# T6G (Grand Teton) — schematic netlist excerpt (pin names and nets, part order shuffled) for the footprints in the layout excerpt that follows; sources: Cadence DE-HDL packaged netlist, KiCad conversion of 04192023_DAF0TMB3IC0_F0TG_MB_C_brd_V02_OCP.brd

C6734  Q_CAP_DIFFBUS  DIFF BUS_0.22UF 6.3V 20% X6S  pkg C0201  page 352 : \1\ = P5E_CPU1_P3_TX_BUF_C_DN<4> ; \2\ = P5E_CPU1_P3_TX_BUF_DN<4>
C134  Q_CAP  0.1UF 10V 10% X7S  pkg C0201  page 323 : A = P1V8_CPU1_RT0_1A ; B = GND
C2189  Q_CAP  22UF 4V 20% X6S  pkg C0402  page 69 : A = PVDDCR_CPU0_P0 ; B = GND
C6599  Q_CAP_DIFFBUS  DIFF BUS_0.22UF 6.3V 20% X6S  pkg C0201  page 308 : \1\ = P5E_CPU0_P3_TX_BUF_C_DP<1> ; \2\ = P5E_CPU0_P3_TX_BUF_DP<1>

(kicad_pcb
	(version 20260206)
	(generator "pcbnew")
	(generator_version "10.0")
	(general
		(thickness 1.6)
		(legacy_teardrops no)
	)
	(paper "A4")
	(title_block
		(title "04192023_DAF0TMB3IC0_F0TG_MB_C_brd_V02_OCP.brd")
		(comment 1 "Grand Teton / footprints 5520-5523 of 8354")
	)
	(layers
		(0 "F.Cu" signal "TOP")
		(4 "In1.Cu" signal "GND")
		(6 "In2.Cu" signal "IN1")
		(8 "In3.Cu" signal "GND1")
		(10 "In4.Cu" signal "IN2")
		(12 "In5.Cu" signal "GND2")
		(14 "In6.Cu" signal "IN3")
		(16 "In7.Cu" signal "GND3")
		(18 "In8.Cu" signal "VCC")
		(20 "In9.Cu" signal "VCC1")
		(22 "In10.Cu" signal "GND4")
		(24 "In11.Cu" signal "IN4")
		(26 "In12.Cu" signal "GND5")
		(28 "In13.Cu" signal "IN5")
		(30 "In14.Cu" signal "GND6")
		(32 "In15.Cu" signal "IN6")
		(34 "In16.Cu" signal "GND7")
		(2 "B.Cu" signal "BOTTOM")
		(9 "F.Adhes" user "F.Adhesive")
		(11 "B.Adhes" user "B.Adhesive")
		(13 "F.Paste" user "Package Geometry/Pastemask Top")
		(15 "B.Paste" user "Package Geometry/Pastemask Bottom")
		(5 "F.SilkS" user "Ref Des/Silkscreen Top")
		(7 "B.SilkS" user "Ref Des/Silkscreen Bottom")
		(1 "F.Mask" user "Board Geometry/Soldermask Top")
		(3 "B.Mask" user "Board Geometry/Soldermask Bottom")
		(17 "Dwgs.User" user "User.Drawings")
		(19 "Cmts.User" user "User.Comments")
		(21 "Eco1.User" user "User.Eco1")
		(23 "Eco2.User" user "User.Eco2")
		(25 "Edge.Cuts" user "Board Geometry/Outline")
		(27 "Margin" user)
		(31 "F.CrtYd" user "Package Geometry/Place Bound Top")
		(29 "B.CrtYd" user "Package Geometry/Place Bound Bottom")
		(35 "F.Fab" user "Ref Des/Assembly Top")
		(33 "B.Fab" user "Ref Des/Assembly Bottom")
	)
	(footprint ""
		(layer "B.Cu")
		(at 128.653286 -408.517344 90)
		(property "Reference" "C6734"
			(at 0 0 90)
			(layer "B.SilkS")
			(hide yes)
			(effects
				(font
					(size 1.27 1.27)
				)
				(justify mirror)
			)
		)
		(property "Value" ""
			(at 0 0 90)
			(layer "B.Fab")
			(effects
				(font
					(size 1.27 1.27)
				)
				(justify mirror)
			)
		)
		(duplicate_pad_numbers_are_jumpers no)
		(fp_line
			(start 0.299974 -0.150114)
			(end -0.299974 -0.150114)
			(stroke
				(width 0.1)
				(type default)
			)
			(layer "B.Fab")
		)
		(fp_line
			(start -0.299974 -0.150114)
			(end -0.299974 0.150114)
			(stroke
				(width 0.1)
				(type default)
			)
			(layer "B.Fab")
		)
		(fp_line
			(start 0.299974 0.150114)
			(end 0.299974 -0.150114)
			(stroke
				(width 0.1)
				(type default)
			)
			(layer "B.Fab")
		)
		(fp_line
			(start -0.299974 0.150114)
			(end 0.299974 0.150114)
			(stroke
				(width 0.1)
				(type default)
			)
			(layer "B.Fab")
		)
		(pad "1" smd rect
			(at 0.2667 0 270)
			(size 0.3048 0.381)
			(layers "B.Cu" "B.Mask" "B.Paste")
			(net "P5E_CPU1_P3_TX_BUF_C_DN<4>")
		)
		(pad "2" smd rect
			(at -0.2667 0 270)
			(size 0.3048 0.381)
			(layers "B.Cu" "B.Mask" "B.Paste")
			(net "P5E_CPU1_P3_TX_BUF_DN<4>")
		)
	)
	(footprint ""
		(layer "B.Cu")
		(at 376.377962 -416.899344 90)
		(property "Reference" "C6599"
			(at 0 0 90)
			(layer "B.SilkS")
			(hide yes)
			(effects
				(font
					(size 1.27 1.27)
				)
				(justify mirror)
			)
		)
		(property "Value" ""
			(at 0 0 90)
			(layer "B.Fab")
			(effects
				(font
					(size 1.27 1.27)
				)
				(justify mirror)
			)
		)
		(duplicate_pad_numbers_are_jumpers no)
		(fp_line
			(start 0.299974 -0.150114)
			(end -0.299974 -0.150114)
			(stroke
				(width 0.1)
				(type default)
			)
			(layer "B.Fab")
		)
		(fp_line
			(start -0.299974 -0.150114)
			(end -0.299974 0.150114)
			(stroke
				(width 0.1)
				(type default)
			)
			(layer "B.Fab")
		)
		(fp_line
			(start 0.299974 0.150114)
			(end 0.299974 -0.150114)
			(stroke
				(width 0.1)
				(type default)
			)
			(layer "B.Fab")
		)
		(fp_line
			(start -0.299974 0.150114)
			(end 0.299974 0.150114)
			(stroke
				(width 0.1)
				(type default)
			)
			(layer "B.Fab")
		)
		(pad "1" smd rect
			(at 0.2667 0 270)
			(size 0.3048 0.381)
			(layers "B.Cu" "B.Mask" "B.Paste")
			(net "P5E_CPU0_P3_TX_BUF_C_DP<1>")
		)
		(pad "2" smd rect
			(at -0.2667 0 270)
			(size 0.3048 0.381)
			(layers "B.Cu" "B.Mask" "B.Paste")
			(net "P5E_CPU0_P3_TX_BUF_DP<1>")
		)
	)
	(footprint ""
		(layer "B.Cu")
		(at 54.578504 -386.766562 90)
		(property "Reference" "C134"
			(at 0 0 90)
			(layer "B.SilkS")
			(hide yes)
			(effects
				(font
					(size 1.27 1.27)
				)
				(justify mirror)
			)
		)
		(property "Value" ""
			(at 0 0 90)
			(layer "B.Fab")
			(effects
				(font
					(size 1.27 1.27)
				)
				(justify mirror)
			)
		)
		(duplicate_pad_numbers_are_jumpers no)
		(fp_line
			(start 0.299974 -0.150114)
			(end -0.299974 -0.150114)
			(stroke
				(width 0.1)
				(type default)
			)
			(layer "B.Fab")
		)
		(fp_line
			(start -0.299974 -0.150114)
			(end -0.299974 0.150114)
			(stroke
				(width 0.1)
				(type default)
			)
			(layer "B.Fab")
		)
		(fp_line
			(start 0.299974 0.150114)
			(end 0.299974 -0.150114)
			(stroke
				(width 0.1)
				(type default)
			)
			(layer "B.Fab")
		)
		(fp_line
			(start -0.299974 0.150114)
			(end 0.299974 0.150114)
			(stroke
				(width 0.1)
				(type default)
			)
			(layer "B.Fab")
		)
		(pad "1" smd rect
			(at 0.2667 0 270)
			(size 0.3048 0.381)
			(layers "B.Cu" "B.Mask" "B.Paste")
			(net "P1V8_CPU1_RT0_1A")
		)
		(pad "2" smd rect
			(at -0.2667 0 270)
			(size 0.3048 0.381)
			(layers "B.Cu" "B.Mask" "B.Paste")
			(net "GND")
		)
	)
	(footprint ""
		(layer "B.Cu")
		(at 349.421958 -245.487952 180)
		(property "Reference" "C2189"
			(at 0 0 0)
			(layer "B.SilkS")
			(hide yes)
			(effects
				(font
					(size 1.27 1.27)
				)
				(justify mirror)
			)
		)
		(property "Value" ""
			(at 0 0 0)
			(layer "B.Fab")
			(effects
				(font
					(size 1.27 1.27)
				)
				(justify mirror)
			)
		)
		(duplicate_pad_numbers_are_jumpers no)
		(fp_line
			(start 0.7874 0.4064)
			(end 0.7874 -0.4064)
			(stroke
				(width 0.1524)
				(type default)
			)
			(layer "B.SilkS")
		)
		(fp_line
			(start 0.7874 -0.4064)
			(end -0.7874 -0.4064)
			(stroke
				(width 0.1524)
				(type default)
			)
			(layer "B.SilkS")
		)
		(fp_line
			(start -0.7874 0.4064)
			(end 0.7874 0.4064)
			(stroke
				(width 0.1524)
				(type default)
			)
			(layer "B.SilkS")
		)
		(fp_line
			(start -0.7874 -0.4064)
			(end -0.7874 0.4064)
			(stroke
				(width 0.1524)
				(type default)
			)
			(layer "B.SilkS")
		)
		(fp_line
			(start 0.67945 0.3048)
			(end 0.67945 -0.305054)
			(stroke
				(width 0.1)
				(type default)
			)
			(layer "B.Fab")
		)
		(fp_line
			(start 0.67945 -0.305054)
			(end 0.12065 -0.305054)
			(stroke
				(width 0.1)
				(type default)
			)
			(layer "B.Fab")
		)
		(fp_line
			(start 0.12065 0.3048)
			(end 0.67945 0.3048)
			(stroke
				(width 0.1)
				(type default)
			)
			(layer "B.Fab")
		)
		(fp_line
			(start 0.12065 0.2794)
			(end 0.12065 0.3048)
			(stroke
				(width 0.1)
				(type default)
			)
			(layer "B.Fab")
		)
		(fp_line
			(start 0.12065 -0.2794)
			(end -0.12065 -0.2794)
			(stroke
				(width 0.1)
				(type default)
			)
			(layer "B.Fab")
		)
		(fp_line
			(start 0.12065 -0.305054)
			(end 0.12065 -0.2794)
			(stroke
				(width 0.1)
				(type default)
			)
			(layer "B.Fab")
		)
		(fp_line
			(start -0.120396 0.3048)
			(end -0.120396 0.2794)
			(stroke
				(width 0.1)
				(type default)
			)
			(layer "B.Fab")
		)
		(fp_line
			(start -0.120396 0.2794)
			(end 0.12065 0.2794)
			(stroke
				(width 0.1)
				(type default)
			)
			(layer "B.Fab")
		)
		(fp_line
			(start -0.12065 -0.2794)
			(end -0.12065 -0.3048)
			(stroke
				(width 0.1)
				(type default)
			)
			(layer "B.Fab")
		)
		(fp_line
			(start -0.12065 -0.3048)
			(end -0.67945 -0.3048)
			(stroke
				(width 0.1)
				(type default)
			)
			(layer "B.Fab")
		)
		(fp_line
			(start -0.67945 0.3048)
			(end -0.120396 0.3048)
			(stroke
				(width 0.1)
				(type default)
			)
			(layer "B.Fab")
		)
		(fp_line
			(start -0.67945 -0.3048)
			(end -0.67945 0.3048)
			(stroke
				(width 0.1)
				(type default)
			)
			(layer "B.Fab")
		)
		(pad "1" smd circle
			(at 0.40005 0)
			(size 0 0)
			(layers "B.Cu" "B.Mask" "B.Paste")
			(net "PVDDCR_CPU0_P0")
		)
		(pad "2" smd circle
			(at -0.40005 0)
			(size 0 0)
			(layers "B.Cu" "B.Mask" "B.Paste")
			(net "GND")
		)
	)
)
